(kicad_pcb
	(version 20241229)
	(generator "pcbnew")
	(generator_version "9.0")
	(general
		(thickness 1.6)
		(legacy_teardrops no)
	)
	(paper "A4")
	(title_block
		(title "LPDDR4 testbed")
		(date "2024-03-26")
		(rev "1.2.2")
		(comment 9 "footprint 16 of 66 (U1), pads 1-88 of 200")
	)
	(layers
		(0 "F.Cu" signal)
		(4 "In1.Cu" power)
		(6 "In2.Cu" power)
		(8 "In3.Cu" signal)
		(10 "In4.Cu" signal)
		(2 "B.Cu" signal)
		(9 "F.Adhes" user "F.Adhesive")
		(11 "B.Adhes" user "B.Adhesive")
		(13 "F.Paste" user)
		(15 "B.Paste" user)
		(5 "F.SilkS" user "F.Silkscreen")
		(7 "B.SilkS" user "B.Silkscreen")
		(1 "F.Mask" user)
		(3 "B.Mask" user)
		(17 "Dwgs.User" user "User.Drawings")
		(19 "Cmts.User" user "User.Comments")
		(21 "Eco1.User" user "User.Eco1")
		(23 "Eco2.User" user "User.Eco2")
		(25 "Edge.Cuts" user)
		(27 "Margin" user)
		(31 "F.CrtYd" user "F.Courtyard")
		(29 "B.CrtYd" user "B.Courtyard")
		(35 "F.Fab" user)
		(33 "B.Fab" user)
	)
	(footprint "antmicro-footprints:BGA-264-200_10x14.5mm_Layout12x22_P0.8x0.65mm"
		(locked yes)
		(layer "F.Cu")
		(at 149.375 86.125 180)
		(descr "http://www.issi.com/WW/pdf/43-46LQ32256A-AL.pdf")
		(property "Reference" "U1"
			(at 5.2 7.575 180)
			(layer "F.SilkS")
			(effects
				(font
					(size 0.7 0.7)
					(thickness 0.15)
				)
				(justify left bottom)
			)
		)
		(property "Value" "MT53E1G32D2NP-046"
			(at -5.5 9 180)
			(layer "F.Fab")
			(effects
				(font
					(size 0.7 0.7)
					(thickness 0.15)
				)
				(justify left bottom)
			)
		)
		(property "Description" "DRAM, Mobile LPDDR4, 32 Gbit, 1G x 32bit, 2.133 GHz, WFBGA, 200 Pins"
			(at 0 0 180)
			(layer "F.Fab")
			(hide yes)
			(effects
				(font
					(size 1.27 1.27)
					(thickness 0.15)
				)
			)
		)
		(property "Author" "Antmicro"
			(at 298.75 172.25 0)
			(layer "F.Fab")
			(hide yes)
			(effects
				(font
					(size 1 1)
					(thickness 0.15)
				)
			)
		)
		(property "License" "Apache-2.0"
			(at 298.75 172.25 0)
			(layer "F.Fab")
			(hide yes)
			(effects
				(font
					(size 1 1)
					(thickness 0.15)
				)
			)
		)
		(property "MPN" "MT53E1G32D2NP-046 WT:A"
			(at 298.75 172.25 0)
			(layer "F.Fab")
			(hide yes)
			(effects
				(font
					(size 1 1)
					(thickness 0.15)
				)
			)
		)
		(property "Manufacturer" "Micron Technology"
			(at 298.75 172.25 0)
			(layer "F.Fab")
			(hide yes)
			(effects
				(font
					(size 1 1)
					(thickness 0.15)
				)
			)
		)
		(sheetname "LPDDR4")
		(sheetfile "lpddr4.kicad_sch")
		(attr smd)
		(pad "A1" smd circle
			(at -4.396 -6.834 180)
			(size 0.27 0.27)
			(layers "F.Cu" "F.Mask" "F.Paste")
			(net 162 "unconnected-(U1A-DNU-PadA1)")
			(pinfunction "DNU")
			(pintype "no_connect")
		)
		(pad "A2" smd circle
			(at -3.596 -6.834 180)
			(size 0.27 0.27)
			(layers "F.Cu" "F.Mask" "F.Paste")
			(net 163 "unconnected-(U1A-DNU-PadA2)")
			(pinfunction "DNU")
			(pintype "no_connect")
		)
		(pad "A3" smd circle
			(at -2.795 -6.834 180)
			(size 0.27 0.27)
			(layers "F.Cu" "F.Mask" "F.Paste")
			(net 36 "GND")
			(pinfunction "VSS")
			(pintype "passive")
		)
		(pad "A4" smd circle
			(at -1.996 -6.834 180)
			(size 0.27 0.27)
			(layers "F.Cu" "F.Mask" "F.Paste")
			(net 188 "VDD2")
			(pinfunction "VDD2")
			(pintype "power_in")
		)
		(pad "A5" smd circle
			(at -1.196 -6.834 180)
			(size 0.27 0.27)
			(layers "F.Cu" "F.Mask" "F.Paste")
			(net 161 "Net-(U1A-ZQ0)")
			(pinfunction "ZQ0")
			(pintype "input")
		)
		(pad "A8" smd circle
			(at 1.205 -6.834 180)
			(size 0.27 0.27)
			(layers "F.Cu" "F.Mask" "F.Paste")
			(net 164 "unconnected-(U1B-NC-PadA8)")
			(pinfunction "NC")
			(pintype "no_connect")
		)
		(pad "A9" smd circle
			(at 2.004 -6.834 180)
			(size 0.27 0.27)
			(layers "F.Cu" "F.Mask" "F.Paste")
			(net 188 "VDD2")
			(pinfunction "VDD2")
			(pintype "passive")
		)
		(pad "A10" smd circle
			(at 2.805 -6.834 180)
			(size 0.27 0.27)
			(layers "F.Cu" "F.Mask" "F.Paste")
			(net 36 "GND")
			(pinfunction "VSS")
			(pintype "power_in")
		)
		(pad "A11" smd circle
			(at 3.604 -6.834 180)
			(size 0.27 0.27)
			(layers "F.Cu" "F.Mask" "F.Paste")
			(net 165 "unconnected-(U1A-DNU-PadA11)")
			(pinfunction "DNU")
			(pintype "no_connect")
		)
		(pad "A12" smd circle
			(at 4.405 -6.834 180)
			(size 0.27 0.27)
			(layers "F.Cu" "F.Mask" "F.Paste")
			(net 166 "unconnected-(U1A-DNU-PadA12)")
			(pinfunction "DNU")
			(pintype "no_connect")
		)
		(pad "AA1" smd circle
			(at -4.396 6.166 180)
			(size 0.27 0.27)
			(layers "F.Cu" "F.Mask" "F.Paste")
			(net 167 "unconnected-(U1B-DNU-PadAA1)")
			(pinfunction "DNU")
			(pintype "no_connect")
		)
		(pad "AA2" smd circle
			(at -3.596 6.166 180)
			(size 0.27 0.27)
			(layers "F.Cu" "F.Mask" "F.Paste")
			(net 168 "unconnected-(U1B-DQ0_B-PadAA2)")
			(pinfunction "DQ0_B")
			(pintype "bidirectional+no_connect")
		)
		(pad "AA3" smd circle
			(at -2.795 6.166 180)
			(size 0.27 0.27)
			(layers "F.Cu" "F.Mask" "F.Paste")
			(net 189 "VDDQ")
			(pinfunction "VDDQ")
			(pintype "passive")
		)
		(pad "AA4" smd circle
			(at -1.996 6.166 180)
			(size 0.27 0.27)
			(layers "F.Cu" "F.Mask" "F.Paste")
			(net 169 "unconnected-(U1B-DQ7_B-PadAA4)")
			(pinfunction "DQ7_B")
			(pintype "bidirectional+no_connect")
		)
		(pad "AA5" smd circle
			(at -1.196 6.166 180)
			(size 0.27 0.27)
			(layers "F.Cu" "F.Mask" "F.Paste")
			(net 189 "VDDQ")
			(pinfunction "VDDQ")
			(pintype "passive")
		)
		(pad "AA8" smd circle
			(at 1.205 6.166 180)
			(size 0.27 0.27)
			(layers "F.Cu" "F.Mask" "F.Paste")
			(net 189 "VDDQ")
			(pinfunction "VDDQ")
			(pintype "passive")
		)
		(pad "AA9" smd circle
			(at 2.004 6.166 180)
			(size 0.27 0.27)
			(layers "F.Cu" "F.Mask" "F.Paste")
			(net 170 "unconnected-(U1B-DQ15_B-PadAA9)")
			(pinfunction "DQ15_B")
			(pintype "bidirectional+no_connect")
		)
		(pad "AA10" smd circle
			(at 2.805 6.166 180)
			(size 0.27 0.27)
			(layers "F.Cu" "F.Mask" "F.Paste")
			(net 189 "VDDQ")
			(pinfunction "VDDQ")
			(pintype "power_in")
		)
		(pad "AA11" smd circle
			(at 3.604 6.166 180)
			(size 0.27 0.27)
			(layers "F.Cu" "F.Mask" "F.Paste")
			(net 171 "unconnected-(U1B-DQ8_B-PadAA11)")
			(pinfunction "DQ8_B")
			(pintype "bidirectional+no_connect")
		)
		(pad "AA12" smd circle
			(at 4.405 6.166 180)
			(size 0.27 0.27)
			(layers "F.Cu" "F.Mask" "F.Paste")
			(net 172 "unconnected-(U1B-DNU-PadAA12)")
			(pinfunction "DNU")
			(pintype "no_connect")
		)
		(pad "AB1" smd circle
			(at -4.396 6.817 180)
			(size 0.27 0.27)
			(layers "F.Cu" "F.Mask" "F.Paste")
			(net 173 "unconnected-(U1B-DNU-PadAB1)")
			(pinfunction "DNU")
			(pintype "no_connect")
		)
		(pad "AB2" smd circle
			(at -3.596 6.817 180)
			(size 0.27 0.27)
			(layers "F.Cu" "F.Mask" "F.Paste")
			(net 174 "unconnected-(U1B-DNU-PadAB2)")
			(pinfunction "DNU")
			(pintype "no_connect")
		)
		(pad "AB3" smd circle
			(at -2.795 6.817 180)
			(size 0.27 0.27)
			(layers "F.Cu" "F.Mask" "F.Paste")
			(net 36 "GND")
			(pinfunction "VSS")
			(pintype "passive")
		)
		(pad "AB4" smd circle
			(at -1.996 6.817 180)
			(size 0.27 0.27)
			(layers "F.Cu" "F.Mask" "F.Paste")
			(net 188 "VDD2")
			(pinfunction "VDD2")
			(pintype "power_in")
		)
		(pad "AB5" smd circle
			(at -1.196 6.817 180)
			(size 0.27 0.27)
			(layers "F.Cu" "F.Mask" "F.Paste")
			(net 36 "GND")
			(pinfunction "VSS")
			(pintype "passive")
		)
		(pad "AB8" smd circle
			(at 1.205 6.817 180)
			(size 0.27 0.27)
			(layers "F.Cu" "F.Mask" "F.Paste")
			(net 36 "GND")
			(pinfunction "VSS")
			(pintype "passive")
		)
		(pad "AB9" smd circle
			(at 2.004 6.817 180)
			(size 0.27 0.27)
			(layers "F.Cu" "F.Mask" "F.Paste")
			(net 188 "VDD2")
			(pinfunction "VDD2")
			(pintype "passive")
		)
		(pad "AB10" smd circle
			(at 2.805 6.817 180)
			(size 0.27 0.27)
			(layers "F.Cu" "F.Mask" "F.Paste")
			(net 36 "GND")
			(pinfunction "VSS")
			(pintype "power_in")
		)
		(pad "AB11" smd circle
			(at 3.604 6.817 180)
			(size 0.27 0.27)
			(layers "F.Cu" "F.Mask" "F.Paste")
			(net 175 "unconnected-(U1B-DNU-PadAB11)")
			(pinfunction "DNU")
			(pintype "no_connect")
		)
		(pad "AB12" smd circle
			(at 4.405 6.817 180)
			(size 0.27 0.27)
			(layers "F.Cu" "F.Mask" "F.Paste")
			(net 176 "unconnected-(U1B-DNU-PadAB12)")
			(pinfunction "DNU")
			(pintype "no_connect")
		)
		(pad "B1" smd circle
			(at -4.396 -6.183 180)
			(size 0.27 0.27)
			(layers "F.Cu" "F.Mask" "F.Paste")
			(net 177 "unconnected-(U1A-DNU-PadB1)")
			(pinfunction "DNU")
			(pintype "no_connect")
		)
		(pad "B2" smd circle
			(at -3.596 -6.183 180)
			(size 0.27 0.27)
			(layers "F.Cu" "F.Mask" "F.Paste")
			(net 190 "DQ00_A")
			(pinfunction "DQ0_A")
			(pintype "bidirectional")
		)
		(pad "B3" smd circle
			(at -2.795 -6.183 180)
			(size 0.27 0.27)
			(layers "F.Cu" "F.Mask" "F.Paste")
			(net 189 "VDDQ")
			(pinfunction "VDDQ")
			(pintype "passive")
		)
		(pad "B4" smd circle
			(at -1.996 -6.183 180)
			(size 0.27 0.27)
			(layers "F.Cu" "F.Mask" "F.Paste")
			(net 198 "DQ07_A")
			(pinfunction "DQ7_A")
			(pintype "bidirectional")
		)
		(pad "B5" smd circle
			(at -1.196 -6.183 180)
			(size 0.27 0.27)
			(layers "F.Cu" "F.Mask" "F.Paste")
			(net 189 "VDDQ")
			(pinfunction "VDDQ")
			(pintype "passive")
		)
		(pad "B8" smd circle
			(at 1.205 -6.183 180)
			(size 0.27 0.27)
			(layers "F.Cu" "F.Mask" "F.Paste")
			(net 189 "VDDQ")
			(pinfunction "VDDQ")
			(pintype "passive")
		)
		(pad "B9" smd circle
			(at 2.004 -6.183 180)
			(size 0.27 0.27)
			(layers "F.Cu" "F.Mask" "F.Paste")
			(net 208 "DQ15_A")
			(pinfunction "DQ15_A")
			(pintype "bidirectional")
		)
		(pad "B10" smd circle
			(at 2.805 -6.183 180)
			(size 0.27 0.27)
			(layers "F.Cu" "F.Mask" "F.Paste")
			(net 189 "VDDQ")
			(pinfunction "VDDQ")
			(pintype "power_in")
		)
		(pad "B11" smd circle
			(at 3.604 -6.183 180)
			(size 0.27 0.27)
			(layers "F.Cu" "F.Mask" "F.Paste")
			(net 212 "DQ08_A")
			(pinfunction "DQ8_A")
			(pintype "bidirectional")
		)
		(pad "B12" smd circle
			(at 4.405 -6.183 180)
			(size 0.27 0.27)
			(layers "F.Cu" "F.Mask" "F.Paste")
			(net 178 "unconnected-(U1A-DNU-PadB12)")
			(pinfunction "DNU")
			(pintype "no_connect")
		)
		(pad "C1" smd circle
			(at -4.396 -5.534 180)
			(size 0.27 0.27)
			(layers "F.Cu" "F.Mask" "F.Paste")
			(net 36 "GND")
			(pinfunction "VSS")
			(pintype "passive")
		)
		(pad "C2" smd circle
			(at -3.596 -5.534 180)
			(size 0.27 0.27)
			(layers "F.Cu" "F.Mask" "F.Paste")
			(net 191 "DQ01_A")
			(pinfunction "DQ1_A")
			(pintype "bidirectional")
		)
		(pad "C3" smd circle
			(at -2.795 -5.534 180)
			(size 0.27 0.27)
			(layers "F.Cu" "F.Mask" "F.Paste")
			(net 201 "DMI_0A")
			(pinfunction "DMI0_A")
			(pintype "bidirectional")
		)
		(pad "C4" smd circle
			(at -1.996 -5.534 180)
			(size 0.27 0.27)
			(layers "F.Cu" "F.Mask" "F.Paste")
			(net 202 "DQ06_A")
			(pinfunction "DQ6_A")
			(pintype "bidirectional")
		)
		(pad "C5" smd circle
			(at -1.196 -5.534 180)
			(size 0.27 0.27)
			(layers "F.Cu" "F.Mask" "F.Paste")
			(net 36 "GND")
			(pinfunction "VSS")
			(pintype "passive")
		)
		(pad "C8" smd circle
			(at 1.205 -5.534 180)
			(size 0.27 0.27)
			(layers "F.Cu" "F.Mask" "F.Paste")
			(net 36 "GND")
			(pinfunction "VSS")
			(pintype "passive")
		)
		(pad "C9" smd circle
			(at 2.004 -5.534 180)
			(size 0.27 0.27)
			(layers "F.Cu" "F.Mask" "F.Paste")
			(net 207 "DQ14_A")
			(pinfunction "DQ14_A")
			(pintype "bidirectional")
		)
		(pad "C10" smd circle
			(at 2.805 -5.534 180)
			(size 0.27 0.27)
			(layers "F.Cu" "F.Mask" "F.Paste")
			(net 211 "DMI_1A")
			(pinfunction "DMI1_A")
			(pintype "bidirectional")
		)
		(pad "C11" smd circle
			(at 3.604 -5.534 180)
			(size 0.27 0.27)
			(layers "F.Cu" "F.Mask" "F.Paste")
			(net 213 "DQ09_A")
			(pinfunction "DQ9_A")
			(pintype "bidirectional")
		)
		(pad "C12" smd circle
			(at 4.405 -5.534 180)
			(size 0.27 0.27)
			(layers "F.Cu" "F.Mask" "F.Paste")
			(net 36 "GND")
			(pinfunction "VSS")
			(pintype "passive")
		)
		(pad "D1" smd circle
			(at -4.396 -4.883 180)
			(size 0.27 0.27)
			(layers "F.Cu" "F.Mask" "F.Paste")
			(net 189 "VDDQ")
			(pinfunction "VDDQ")
			(pintype "passive")
		)
		(pad "D2" smd circle
			(at -3.596 -4.883 180)
			(size 0.27 0.27)
			(layers "F.Cu" "F.Mask" "F.Paste")
			(net 36 "GND")
			(pinfunction "VSS")
			(pintype "passive")
		)
		(pad "D3" smd circle
			(at -2.795 -4.883 180)
			(size 0.27 0.27)
			(layers "F.Cu" "F.Mask" "F.Paste")
			(net 196 "DQ_S0_TA")
			(pinfunction "DQS0_T_A")
			(pintype "bidirectional")
		)
		(pad "D4" smd circle
			(at -1.996 -4.883 180)
			(size 0.27 0.27)
			(layers "F.Cu" "F.Mask" "F.Paste")
			(net 36 "GND")
			(pinfunction "VSS")
			(pintype "passive")
		)
		(pad "D5" smd circle
			(at -1.196 -4.883 180)
			(size 0.27 0.27)
			(layers "F.Cu" "F.Mask" "F.Paste")
			(net 189 "VDDQ")
			(pinfunction "VDDQ")
			(pintype "passive")
		)
		(pad "D8" smd circle
			(at 1.205 -4.883 180)
			(size 0.27 0.27)
			(layers "F.Cu" "F.Mask" "F.Paste")
			(net 189 "VDDQ")
			(pinfunction "VDDQ")
			(pintype "passive")
		)
		(pad "D9" smd circle
			(at 2.004 -4.883 180)
			(size 0.27 0.27)
			(layers "F.Cu" "F.Mask" "F.Paste")
			(net 36 "GND")
			(pinfunction "VSS")
			(pintype "passive")
		)
		(pad "D10" smd circle
			(at 2.805 -4.883 180)
			(size 0.27 0.27)
			(layers "F.Cu" "F.Mask" "F.Paste")
			(net 209 "DQ_S1_TA")
			(pinfunction "DQS1_T_A")
			(pintype "bidirectional")
		)
		(pad "D11" smd circle
			(at 3.604 -4.883 180)
			(size 0.27 0.27)
			(layers "F.Cu" "F.Mask" "F.Paste")
			(net 36 "GND")
			(pinfunction "VSS")
			(pintype "passive")
		)
		(pad "D12" smd circle
			(at 4.405 -4.883 180)
			(size 0.27 0.27)
			(layers "F.Cu" "F.Mask" "F.Paste")
			(net 189 "VDDQ")
			(pinfunction "VDDQ")
			(pintype "passive")
		)
		(pad "E1" smd circle
			(at -4.396 -4.233 180)
			(size 0.27 0.27)
			(layers "F.Cu" "F.Mask" "F.Paste")
			(net 36 "GND")
			(pinfunction "VSS")
			(pintype "passive")
		)
		(pad "E2" smd circle
			(at -3.596 -4.233 180)
			(size 0.27 0.27)
			(layers "F.Cu" "F.Mask" "F.Paste")
			(net 193 "DQ02_A")
			(pinfunction "DQ2_A")
			(pintype "bidirectional")
		)
		(pad "E3" smd circle
			(at -2.795 -4.233 180)
			(size 0.27 0.27)
			(layers "F.Cu" "F.Mask" "F.Paste")
			(net 197 "DQ_S0_CA")
			(pinfunction "DQS0_C_A")
			(pintype "bidirectional")
		)
		(pad "E4" smd circle
			(at -1.996 -4.233 180)
			(size 0.27 0.27)
			(layers "F.Cu" "F.Mask" "F.Paste")
			(net 203 "DQ05_A")
			(pinfunction "DQ5_A")
			(pintype "bidirectional")
		)
		(pad "E5" smd circle
			(at -1.196 -4.233 180)
			(size 0.27 0.27)
			(layers "F.Cu" "F.Mask" "F.Paste")
			(net 36 "GND")
			(pinfunction "VSS")
			(pintype "passive")
		)
		(pad "E8" smd circle
			(at 1.205 -4.233 180)
			(size 0.27 0.27)
			(layers "F.Cu" "F.Mask" "F.Paste")
			(net 36 "GND")
			(pinfunction "VSS")
			(pintype "passive")
		)
		(pad "E9" smd circle
			(at 2.004 -4.233 180)
			(size 0.27 0.27)
			(layers "F.Cu" "F.Mask" "F.Paste")
			(net 206 "DQ13_A")
			(pinfunction "DQ13_A")
			(pintype "bidirectional")
		)
		(pad "E10" smd circle
			(at 2.805 -4.233 180)
			(size 0.27 0.27)
			(layers "F.Cu" "F.Mask" "F.Paste")
			(net 210 "DQ_S1_CA")
			(pinfunction "DQS1_C_A")
			(pintype "bidirectional")
		)
		(pad "E11" smd circle
			(at 3.604 -4.233 180)
			(size 0.27 0.27)
			(layers "F.Cu" "F.Mask" "F.Paste")
			(net 215 "DQ10_A")
			(pinfunction "DQ10_A")
			(pintype "bidirectional")
		)
		(pad "E12" smd circle
			(at 4.405 -4.233 180)
			(size 0.27 0.27)
			(layers "F.Cu" "F.Mask" "F.Paste")
			(net 36 "GND")
			(pinfunction "VSS")
			(pintype "passive")
		)
		(pad "F1" smd circle
			(at -4.396 -3.584 180)
			(size 0.27 0.27)
			(layers "F.Cu" "F.Mask" "F.Paste")
			(net 187 "VDD1")
			(pinfunction "VDD1")
			(pintype "power_in")
		)
		(pad "F2" smd circle
			(at -3.596 -3.584 180)
			(size 0.27 0.27)
			(layers "F.Cu" "F.Mask" "F.Paste")
			(net 195 "DQ03_A")
			(pinfunction "DQ3_A")
			(pintype "bidirectional")
		)
		(pad "F3" smd circle
			(at -2.795 -3.584 180)
			(size 0.27 0.27)
			(layers "F.Cu" "F.Mask" "F.Paste")
			(net 189 "VDDQ")
			(pinfunction "VDDQ")
			(pintype "passive")
		)
		(pad "F4" smd circle
			(at -1.996 -3.584 180)
			(size 0.27 0.27)
			(layers "F.Cu" "F.Mask" "F.Paste")
			(net 204 "DQ04_A")
			(pinfunction "DQ4_A")
			(pintype "bidirectional")
		)
		(pad "F5" smd circle
			(at -1.196 -3.584 180)
			(size 0.27 0.27)
			(layers "F.Cu" "F.Mask" "F.Paste")
			(net 188 "VDD2")
			(pinfunction "VDD2")
			(pintype "passive")
		)
		(pad "F8" smd circle
			(at 1.205 -3.584 180)
			(size 0.27 0.27)
			(layers "F.Cu" "F.Mask" "F.Paste")
			(net 188 "VDD2")
			(pinfunction "VDD2")
			(pintype "passive")
		)
		(pad "F9" smd circle
			(at 2.004 -3.584 180)
			(size 0.27 0.27)
			(layers "F.Cu" "F.Mask" "F.Paste")
			(net 205 "DQ12_A")
			(pinfunction "DQ12_A")
			(pintype "bidirectional")
		)
		(pad "F10" smd circle
			(at 2.805 -3.584 180)
			(size 0.27 0.27)
			(layers "F.Cu" "F.Mask" "F.Paste")
			(net 189 "VDDQ")
			(pinfunction "VDDQ")
			(pintype "passive")
		)
		(pad "F11" smd circle
			(at 3.604 -3.584 180)
			(size 0.27 0.27)
			(layers "F.Cu" "F.Mask" "F.Paste")
			(net 217 "DQ11_A")
			(pinfunction "DQ11_A")
			(pintype "bidirectional")
		)
		(pad "F12" smd circle
			(at 4.405 -3.584 180)
			(size 0.27 0.27)
			(layers "F.Cu" "F.Mask" "F.Paste")
			(net 187 "VDD1")
			(pinfunction "VDD1")
			(pintype "passive")
		)
		(pad "G1" smd circle
			(at -4.396 -2.934 180)
			(size 0.27 0.27)
			(layers "F.Cu" "F.Mask" "F.Paste")
			(net 36 "GND")
			(pinfunction "VSS")
			(pintype "passive")
		)
		(pad "G2" smd circle
			(at -3.596 -2.934 180)
			(size 0.27 0.27)
			(layers "F.Cu" "F.Mask" "F.Paste")
			(net 158 "Net-(U1A-ODT_CA_A)")
			(pinfunction "ODT_CA_A")
			(pintype "input")
		)
		(pad "G3" smd circle
			(at -2.795 -2.934 180)
			(size 0.27 0.27)
			(layers "F.Cu" "F.Mask" "F.Paste")
			(net 36 "GND")
			(pinfunction "VSS")
			(pintype "passive")
		)
		(pad "G4" smd circle
			(at -1.996 -2.934 180)
			(size 0.27 0.27)
			(layers "F.Cu" "F.Mask" "F.Paste")
			(net 187 "VDD1")
			(pinfunction "VDD1")
			(pintype "passive")
		)
		(pad "G5" smd circle
			(at -1.196 -2.934 180)
			(size 0.27 0.27)
			(layers "F.Cu" "F.Mask" "F.Paste")
			(net 36 "GND")
			(pinfunction "VSS")
			(pintype "passive")
		)
		(pad "G8" smd circle
			(at 1.205 -2.934 180)
			(size 0.27 0.27)
			(layers "F.Cu" "F.Mask" "F.Paste")
			(net 36 "GND")
			(pinfunction "VSS")
			(pintype "passive")
		)
		(pad "G9" smd circle
			(at 2.004 -2.934 180)
			(size 0.27 0.27)
			(layers "F.Cu" "F.Mask" "F.Paste")
			(net 187 "VDD1")
			(pinfunction "VDD1")
			(pintype "passive")
		)
		(pad "G10" smd circle
			(at 2.805 -2.934 180)
			(size 0.27 0.27)
			(layers "F.Cu" "F.Mask" "F.Paste")
			(net 36 "GND")
			(pinfunction "VSS")
			(pintype "passive")
		)
	)
)
